(kicad_pcb
	(version 20260206)
	(generator "pcbnew")
	(generator_version "10.0")
	(general
		(thickness 1.6)
		(legacy_teardrops no)
	)
	(paper "A4")
	(title_block
		(title "01162023_DA0F0TEBIF0_F0T_Expander_BD_F_brd_V02_OCP.brd")
		(comment 1 "Grand Teton / footprints 4705-4711 of 9728")
	)
	(layers
		(0 "F.Cu" signal "TOP")
		(4 "In1.Cu" signal "GND")
		(6 "In2.Cu" signal "VCC")
		(8 "In3.Cu" signal "VCC1")
		(10 "In4.Cu" signal "GND1")
		(12 "In5.Cu" signal "IN1")
		(14 "In6.Cu" signal "GND2")
		(16 "In7.Cu" signal "IN2")
		(18 "In8.Cu" signal "GND3")
		(20 "In9.Cu" signal "IN3")
		(22 "In10.Cu" signal "GND4")
		(24 "In11.Cu" signal "IN4")
		(26 "In12.Cu" signal "GND5")
		(28 "In13.Cu" signal "IN5")
		(30 "In14.Cu" signal "GND6")
		(32 "In15.Cu" signal "IN6")
		(34 "In16.Cu" signal "GND7")
		(2 "B.Cu" signal "BOTTOM")
		(9 "F.Adhes" user "F.Adhesive")
		(11 "B.Adhes" user "B.Adhesive")
		(13 "F.Paste" user "Package Geometry/Pastemask Top")
		(15 "B.Paste" user "Package Geometry/Pastemask Bottom")
		(5 "F.SilkS" user "Ref Des/Silkscreen Top")
		(7 "B.SilkS" user "Ref Des/Silkscreen Bottom")
		(1 "F.Mask" user "Board Geometry/Soldermask Top")
		(3 "B.Mask" user "Board Geometry/Soldermask Bottom")
		(17 "Dwgs.User" user "User.Drawings")
		(19 "Cmts.User" user "User.Comments")
		(21 "Eco1.User" user "User.Eco1")
		(23 "Eco2.User" user "User.Eco2")
		(25 "Edge.Cuts" user "Board Geometry/Outline")
		(27 "Margin" user)
		(31 "F.CrtYd" user "Package Geometry/Place Bound Top")
		(29 "B.CrtYd" user "Package Geometry/Place Bound Bottom")
		(35 "F.Fab" user "Ref Des/Assembly Top")
		(33 "B.Fab" user "Ref Des/Assembly Bottom")
	)
	(footprint ""
		(layer "F.Cu")
		(at 258.401566 -334.013048 -90)
		(property "Reference" "R6791"
			(at 0 0 270)
			(layer "F.SilkS")
			(hide yes)
			(effects
				(font
					(size 1.27 1.27)
				)
			)
		)
		(property "Value" ""
			(at 0 0 270)
			(layer "F.Fab")
			(effects
				(font
					(size 1.27 1.27)
				)
			)
		)
		(duplicate_pad_numbers_are_jumpers no)
		(fp_line
			(start -0.7874 0.4064)
			(end -0.7874 -0.4064)
			(stroke
				(width 0.1524)
				(type default)
			)
			(layer "F.SilkS")
		)
		(fp_line
			(start 0.7874 0.4064)
			(end -0.7874 0.4064)
			(stroke
				(width 0.1524)
				(type default)
			)
			(layer "F.SilkS")
		)
		(fp_line
			(start -0.7874 -0.4064)
			(end 0.7874 -0.4064)
			(stroke
				(width 0.1524)
				(type default)
			)
			(layer "F.SilkS")
		)
		(fp_line
			(start 0.7874 -0.4064)
			(end 0.7874 0.4064)
			(stroke
				(width 0.1524)
				(type default)
			)
			(layer "F.SilkS")
		)
		(fp_line
			(start -0.67945 0.3048)
			(end -0.67945 -0.305054)
			(stroke
				(width 0.1)
				(type default)
			)
			(layer "F.Fab")
		)
		(fp_line
			(start -0.12065 0.3048)
			(end -0.67945 0.3048)
			(stroke
				(width 0.1)
				(type default)
			)
			(layer "F.Fab")
		)
		(fp_line
			(start 0.120396 0.3048)
			(end 0.120396 0.2794)
			(stroke
				(width 0.1)
				(type default)
			)
			(layer "F.Fab")
		)
		(fp_line
			(start 0.67945 0.3048)
			(end 0.120396 0.3048)
			(stroke
				(width 0.1)
				(type default)
			)
			(layer "F.Fab")
		)
		(fp_line
			(start -0.12065 0.2794)
			(end -0.12065 0.3048)
			(stroke
				(width 0.1)
				(type default)
			)
			(layer "F.Fab")
		)
		(fp_line
			(start 0.120396 0.2794)
			(end -0.12065 0.2794)
			(stroke
				(width 0.1)
				(type default)
			)
			(layer "F.Fab")
		)
		(fp_line
			(start -0.12065 -0.2794)
			(end 0.12065 -0.2794)
			(stroke
				(width 0.1)
				(type default)
			)
			(layer "F.Fab")
		)
		(fp_line
			(start 0.12065 -0.2794)
			(end 0.12065 -0.3048)
			(stroke
				(width 0.1)
				(type default)
			)
			(layer "F.Fab")
		)
		(fp_line
			(start 0.12065 -0.3048)
			(end 0.67945 -0.3048)
			(stroke
				(width 0.1)
				(type default)
			)
			(layer "F.Fab")
		)
		(fp_line
			(start 0.67945 -0.3048)
			(end 0.67945 0.3048)
			(stroke
				(width 0.1)
				(type default)
			)
			(layer "F.Fab")
		)
		(fp_line
			(start -0.67945 -0.305054)
			(end -0.12065 -0.305054)
			(stroke
				(width 0.1)
				(type default)
			)
			(layer "F.Fab")
		)
		(fp_line
			(start -0.12065 -0.305054)
			(end -0.12065 -0.2794)
			(stroke
				(width 0.1)
				(type default)
			)
			(layer "F.Fab")
		)
		(pad "1" smd circle
			(at -0.40005 0 270)
			(size 0 0)
			(layers "F.Cu" "F.Mask" "F.Paste")
			(net "HSC_CSOUT")
		)
		(pad "2" smd circle
			(at 0.40005 0 270)
			(size 0 0)
			(layers "F.Cu" "F.Mask" "F.Paste")
			(net "HSC_OC_VOL")
		)
	)
	(footprint ""
		(layer "F.Cu")
		(at 318.62776 -302.863504 180)
		(property "Reference" "R3975"
			(at 0 0 180)
			(layer "F.SilkS")
			(hide yes)
			(effects
				(font
					(size 1.27 1.27)
				)
			)
		)
		(property "Value" ""
			(at 0 0 180)
			(layer "F.Fab")
			(effects
				(font
					(size 1.27 1.27)
				)
			)
		)
		(duplicate_pad_numbers_are_jumpers no)
		(fp_line
			(start 0.7874 0.4064)
			(end -0.7874 0.4064)
			(stroke
				(width 0.1524)
				(type default)
			)
			(layer "F.SilkS")
		)
		(fp_line
			(start 0.7874 -0.4064)
			(end 0.7874 0.4064)
			(stroke
				(width 0.1524)
				(type default)
			)
			(layer "F.SilkS")
		)
		(fp_line
			(start -0.7874 0.4064)
			(end -0.7874 -0.4064)
			(stroke
				(width 0.1524)
				(type default)
			)
			(layer "F.SilkS")
		)
		(fp_line
			(start -0.7874 -0.4064)
			(end 0.7874 -0.4064)
			(stroke
				(width 0.1524)
				(type default)
			)
			(layer "F.SilkS")
		)
		(fp_line
			(start 0.67945 0.3048)
			(end 0.120396 0.3048)
			(stroke
				(width 0.1)
				(type default)
			)
			(layer "F.Fab")
		)
		(fp_line
			(start 0.67945 -0.3048)
			(end 0.67945 0.3048)
			(stroke
				(width 0.1)
				(type default)
			)
			(layer "F.Fab")
		)
		(fp_line
			(start 0.12065 -0.2794)
			(end 0.12065 -0.3048)
			(stroke
				(width 0.1)
				(type default)
			)
			(layer "F.Fab")
		)
		(fp_line
			(start 0.12065 -0.3048)
			(end 0.67945 -0.3048)
			(stroke
				(width 0.1)
				(type default)
			)
			(layer "F.Fab")
		)
		(fp_line
			(start 0.120396 0.3048)
			(end 0.120396 0.2794)
			(stroke
				(width 0.1)
				(type default)
			)
			(layer "F.Fab")
		)
		(fp_line
			(start 0.120396 0.2794)
			(end -0.12065 0.2794)
			(stroke
				(width 0.1)
				(type default)
			)
			(layer "F.Fab")
		)
		(fp_line
			(start -0.12065 0.3048)
			(end -0.67945 0.3048)
			(stroke
				(width 0.1)
				(type default)
			)
			(layer "F.Fab")
		)
		(fp_line
			(start -0.12065 0.2794)
			(end -0.12065 0.3048)
			(stroke
				(width 0.1)
				(type default)
			)
			(layer "F.Fab")
		)
		(fp_line
			(start -0.12065 -0.2794)
			(end 0.12065 -0.2794)
			(stroke
				(width 0.1)
				(type default)
			)
			(layer "F.Fab")
		)
		(fp_line
			(start -0.12065 -0.305054)
			(end -0.12065 -0.2794)
			(stroke
				(width 0.1)
				(type default)
			)
			(layer "F.Fab")
		)
		(fp_line
			(start -0.67945 0.3048)
			(end -0.67945 -0.305054)
			(stroke
				(width 0.1)
				(type default)
			)
			(layer "F.Fab")
		)
		(fp_line
			(start -0.67945 -0.305054)
			(end -0.12065 -0.305054)
			(stroke
				(width 0.1)
				(type default)
			)
			(layer "F.Fab")
		)
		(pad "1" smd circle
			(at -0.40005 0 180)
			(size 0 0)
			(layers "F.Cu" "F.Mask" "F.Paste")
			(net "SMB_PEX2_SLAVE_SCL")
		)
		(pad "2" smd circle
			(at 0.40005 0 180)
			(size 0 0)
			(layers "F.Cu" "F.Mask" "F.Paste")
			(net "SMB_PEX2_R_SCL")
		)
	)
	(footprint ""
		(layer "F.Cu")
		(at 384.938524 -120.113298)
		(property "Reference" "C681"
			(at 0 0 0)
			(layer "F.SilkS")
			(hide yes)
			(effects
				(font
					(size 1.27 1.27)
				)
			)
		)
		(property "Value" ""
			(at 0 0 0)
			(layer "F.Fab")
			(effects
				(font
					(size 1.27 1.27)
				)
			)
		)
		(duplicate_pad_numbers_are_jumpers no)
		(fp_line
			(start -0.299974 -0.150114)
			(end 0.299974 -0.150114)
			(stroke
				(width 0.1)
				(type default)
			)
			(layer "F.Fab")
		)
		(fp_line
			(start -0.299974 0.150114)
			(end -0.299974 -0.150114)
			(stroke
				(width 0.1)
				(type default)
			)
			(layer "F.Fab")
		)
		(fp_line
			(start 0.299974 -0.150114)
			(end 0.299974 0.150114)
			(stroke
				(width 0.1)
				(type default)
			)
			(layer "F.Fab")
		)
		(fp_line
			(start 0.299974 0.150114)
			(end -0.299974 0.150114)
			(stroke
				(width 0.1)
				(type default)
			)
			(layer "F.Fab")
		)
		(pad "1" smd rect
			(at -0.2667 0)
			(size 0.3048 0.381)
			(layers "F.Cu" "F.Mask" "F.Paste")
			(net "P5E_PEX3_STN1_TX_DN<24>")
		)
		(pad "2" smd rect
			(at 0.2667 0)
			(size 0.3048 0.381)
			(layers "F.Cu" "F.Mask" "F.Paste")
			(net "P5E_PEX3_STN1_TX_C_DN<24>")
		)
	)
	(footprint ""
		(layer "F.Cu")
		(at 431.032412 -343.952322 90)
		(property "Reference" "C2459"
			(at 0 0 90)
			(layer "F.SilkS")
			(hide yes)
			(effects
				(font
					(size 1.27 1.27)
				)
			)
		)
		(property "Value" ""
			(at 0 0 90)
			(layer "F.Fab")
			(effects
				(font
					(size 1.27 1.27)
				)
			)
		)
		(duplicate_pad_numbers_are_jumpers no)
		(fp_line
			(start 0.299974 -0.150114)
			(end 0.299974 0.150114)
			(stroke
				(width 0.1)
				(type default)
			)
			(layer "F.Fab")
		)
		(fp_line
			(start -0.299974 -0.150114)
			(end 0.299974 -0.150114)
			(stroke
				(width 0.1)
				(type default)
			)
			(layer "F.Fab")
		)
		(fp_line
			(start 0.299974 0.150114)
			(end -0.299974 0.150114)
			(stroke
				(width 0.1)
				(type default)
			)
			(layer "F.Fab")
		)
		(fp_line
			(start -0.299974 0.150114)
			(end -0.299974 -0.150114)
			(stroke
				(width 0.1)
				(type default)
			)
			(layer "F.Fab")
		)
		(pad "1" smd rect
			(at -0.2667 0 90)
			(size 0.3048 0.381)
			(layers "F.Cu" "F.Mask" "F.Paste")
			(net "P5E_PEX3_STN4_TX_DP<69>")
		)
		(pad "2" smd rect
			(at 0.2667 0 90)
			(size 0.3048 0.381)
			(layers "F.Cu" "F.Mask" "F.Paste")
			(net "P5E_PEX3_STN4_TX_C_DP<69>")
		)
	)
	(footprint ""
		(layer "F.Cu")
		(at 205.391766 -356.811326)
		(property "Reference" "R493"
			(at 0 0 0)
			(layer "F.SilkS")
			(hide yes)
			(effects
				(font
					(size 1.27 1.27)
				)
			)
		)
		(property "Value" ""
			(at 0 0 0)
			(layer "F.Fab")
			(effects
				(font
					(size 1.27 1.27)
				)
			)
		)
		(duplicate_pad_numbers_are_jumpers no)
		(fp_line
			(start -0.7874 -0.4064)
			(end 0.7874 -0.4064)
			(stroke
				(width 0.1524)
				(type default)
			)
			(layer "F.SilkS")
		)
		(fp_line
			(start -0.7874 0.4064)
			(end -0.7874 -0.4064)
			(stroke
				(width 0.1524)
				(type default)
			)
			(layer "F.SilkS")
		)
		(fp_line
			(start 0.7874 -0.4064)
			(end 0.7874 0.4064)
			(stroke
				(width 0.1524)
				(type default)
			)
			(layer "F.SilkS")
		)
		(fp_line
			(start 0.7874 0.4064)
			(end -0.7874 0.4064)
			(stroke
				(width 0.1524)
				(type default)
			)
			(layer "F.SilkS")
		)
		(fp_line
			(start -0.67945 -0.305054)
			(end -0.12065 -0.305054)
			(stroke
				(width 0.1)
				(type default)
			)
			(layer "F.Fab")
		)
		(fp_line
			(start -0.67945 0.3048)
			(end -0.67945 -0.305054)
			(stroke
				(width 0.1)
				(type default)
			)
			(layer "F.Fab")
		)
		(fp_line
			(start -0.12065 -0.305054)
			(end -0.12065 -0.2794)
			(stroke
				(width 0.1)
				(type default)
			)
			(layer "F.Fab")
		)
		(fp_line
			(start -0.12065 -0.2794)
			(end 0.12065 -0.2794)
			(stroke
				(width 0.1)
				(type default)
			)
			(layer "F.Fab")
		)
		(fp_line
			(start -0.12065 0.2794)
			(end -0.12065 0.3048)
			(stroke
				(width 0.1)
				(type default)
			)
			(layer "F.Fab")
		)
		(fp_line
			(start -0.12065 0.3048)
			(end -0.67945 0.3048)
			(stroke
				(width 0.1)
				(type default)
			)
			(layer "F.Fab")
		)
		(fp_line
			(start 0.120396 0.2794)
			(end -0.12065 0.2794)
			(stroke
				(width 0.1)
				(type default)
			)
			(layer "F.Fab")
		)
		(fp_line
			(start 0.120396 0.3048)
			(end 0.120396 0.2794)
			(stroke
				(width 0.1)
				(type default)
			)
			(layer "F.Fab")
		)
		(fp_line
			(start 0.12065 -0.3048)
			(end 0.67945 -0.3048)
			(stroke
				(width 0.1)
				(type default)
			)
			(layer "F.Fab")
		)
		(fp_line
			(start 0.12065 -0.2794)
			(end 0.12065 -0.3048)
			(stroke
				(width 0.1)
				(type default)
			)
			(layer "F.Fab")
		)
		(fp_line
			(start 0.67945 -0.3048)
			(end 0.67945 0.3048)
			(stroke
				(width 0.1)
				(type default)
			)
			(layer "F.Fab")
		)
		(fp_line
			(start 0.67945 0.3048)
			(end 0.120396 0.3048)
			(stroke
				(width 0.1)
				(type default)
			)
			(layer "F.Fab")
		)
		(pad "1" smd circle
			(at -0.40005 0)
			(size 0 0)
			(layers "F.Cu" "F.Mask" "F.Paste")
			(net "HSC_D_OC")
		)
		(pad "2" smd circle
			(at 0.40005 0)
			(size 0 0)
			(layers "F.Cu" "F.Mask" "F.Paste")
			(net "HSC_D_OC_R")
		)
	)
	(footprint ""
		(layer "F.Cu")
		(at 352.826828 -53.697124 -90)
		(property "Reference" "PC544"
			(at 0 0 270)
			(layer "F.SilkS")
			(hide yes)
			(effects
				(font
					(size 1.27 1.27)
				)
			)
		)
		(property "Value" ""
			(at 0 0 270)
			(layer "F.Fab")
			(effects
				(font
					(size 1.27 1.27)
				)
			)
		)
		(duplicate_pad_numbers_are_jumpers no)
		(fp_line
			(start -0.7874 0.4064)
			(end -0.7874 -0.4064)
			(stroke
				(width 0.1524)
				(type default)
			)
			(layer "F.SilkS")
		)
		(fp_line
			(start 0.7874 0.4064)
			(end -0.7874 0.4064)
			(stroke
				(width 0.1524)
				(type default)
			)
			(layer "F.SilkS")
		)
		(fp_line
			(start -0.7874 -0.4064)
			(end 0.7874 -0.4064)
			(stroke
				(width 0.1524)
				(type default)
			)
			(layer "F.SilkS")
		)
		(fp_line
			(start 0.7874 -0.4064)
			(end 0.7874 0.4064)
			(stroke
				(width 0.1524)
				(type default)
			)
			(layer "F.SilkS")
		)
		(fp_line
			(start -0.67945 0.3048)
			(end -0.67945 -0.305054)
			(stroke
				(width 0.1)
				(type default)
			)
			(layer "F.Fab")
		)
		(fp_line
			(start -0.12065 0.3048)
			(end -0.67945 0.3048)
			(stroke
				(width 0.1)
				(type default)
			)
			(layer "F.Fab")
		)
		(fp_line
			(start 0.120396 0.3048)
			(end 0.120396 0.2794)
			(stroke
				(width 0.1)
				(type default)
			)
			(layer "F.Fab")
		)
		(fp_line
			(start 0.67945 0.3048)
			(end 0.120396 0.3048)
			(stroke
				(width 0.1)
				(type default)
			)
			(layer "F.Fab")
		)
		(fp_line
			(start -0.12065 0.2794)
			(end -0.12065 0.3048)
			(stroke
				(width 0.1)
				(type default)
			)
			(layer "F.Fab")
		)
		(fp_line
			(start 0.120396 0.2794)
			(end -0.12065 0.2794)
			(stroke
				(width 0.1)
				(type default)
			)
			(layer "F.Fab")
		)
		(fp_line
			(start -0.12065 -0.2794)
			(end 0.12065 -0.2794)
			(stroke
				(width 0.1)
				(type default)
			)
			(layer "F.Fab")
		)
		(fp_line
			(start 0.12065 -0.2794)
			(end 0.12065 -0.3048)
			(stroke
				(width 0.1)
				(type default)
			)
			(layer "F.Fab")
		)
		(fp_line
			(start 0.12065 -0.3048)
			(end 0.67945 -0.3048)
			(stroke
				(width 0.1)
				(type default)
			)
			(layer "F.Fab")
		)
		(fp_line
			(start 0.67945 -0.3048)
			(end 0.67945 0.3048)
			(stroke
				(width 0.1)
				(type default)
			)
			(layer "F.Fab")
		)
		(fp_line
			(start -0.67945 -0.305054)
			(end -0.12065 -0.305054)
			(stroke
				(width 0.1)
				(type default)
			)
			(layer "F.Fab")
		)
		(fp_line
			(start -0.12065 -0.305054)
			(end -0.12065 -0.2794)
			(stroke
				(width 0.1)
				(type default)
			)
			(layer "F.Fab")
		)
		(pad "1" smd circle
			(at -0.40005 0 270)
			(size 0 0)
			(layers "F.Cu" "F.Mask" "F.Paste")
			(net "P3V3_AUX")
		)
		(pad "2" smd circle
			(at 0.40005 0 270)
			(size 0 0)
			(layers "F.Cu" "F.Mask" "F.Paste")
			(net "GND")
		)
	)
	(footprint ""
		(layer "F.Cu")
		(at 201.635868 -289.230816 -90)
		(property "Reference" "R6393"
			(at 0 0 270)
			(layer "F.SilkS")
			(hide yes)
			(effects
				(font
					(size 1.27 1.27)
				)
			)
		)
		(property "Value" ""
			(at 0 0 270)
			(layer "F.Fab")
			(effects
				(font
					(size 1.27 1.27)
				)
			)
		)
		(duplicate_pad_numbers_are_jumpers no)
		(fp_line
			(start -0.7874 0.4064)
			(end -0.7874 -0.4064)
			(stroke
				(width 0.1524)
				(type default)
			)
			(layer "F.SilkS")
		)
		(fp_line
			(start 0.7874 0.4064)
			(end -0.7874 0.4064)
			(stroke
				(width 0.1524)
				(type default)
			)
			(layer "F.SilkS")
		)
		(fp_line
			(start -0.7874 -0.4064)
			(end 0.7874 -0.4064)
			(stroke
				(width 0.1524)
				(type default)
			)
			(layer "F.SilkS")
		)
		(fp_line
			(start 0.7874 -0.4064)
			(end 0.7874 0.4064)
			(stroke
				(width 0.1524)
				(type default)
			)
			(layer "F.SilkS")
		)
		(fp_line
			(start -0.67945 0.3048)
			(end -0.67945 -0.305054)
			(stroke
				(width 0.1)
				(type default)
			)
			(layer "F.Fab")
		)
		(fp_line
			(start -0.12065 0.3048)
			(end -0.67945 0.3048)
			(stroke
				(width 0.1)
				(type default)
			)
			(layer "F.Fab")
		)
		(fp_line
			(start 0.120396 0.3048)
			(end 0.120396 0.2794)
			(stroke
				(width 0.1)
				(type default)
			)
			(layer "F.Fab")
		)
		(fp_line
			(start 0.67945 0.3048)
			(end 0.120396 0.3048)
			(stroke
				(width 0.1)
				(type default)
			)
			(layer "F.Fab")
		)
		(fp_line
			(start -0.12065 0.2794)
			(end -0.12065 0.3048)
			(stroke
				(width 0.1)
				(type default)
			)
			(layer "F.Fab")
		)
		(fp_line
			(start 0.120396 0.2794)
			(end -0.12065 0.2794)
			(stroke
				(width 0.1)
				(type default)
			)
			(layer "F.Fab")
		)
		(fp_line
			(start -0.12065 -0.2794)
			(end 0.12065 -0.2794)
			(stroke
				(width 0.1)
				(type default)
			)
			(layer "F.Fab")
		)
		(fp_line
			(start 0.12065 -0.2794)
			(end 0.12065 -0.3048)
			(stroke
				(width 0.1)
				(type default)
			)
			(layer "F.Fab")
		)
		(fp_line
			(start 0.12065 -0.3048)
			(end 0.67945 -0.3048)
			(stroke
				(width 0.1)
				(type default)
			)
			(layer "F.Fab")
		)
		(fp_line
			(start 0.67945 -0.3048)
			(end 0.67945 0.3048)
			(stroke
				(width 0.1)
				(type default)
			)
			(layer "F.Fab")
		)
		(fp_line
			(start -0.67945 -0.305054)
			(end -0.12065 -0.305054)
			(stroke
				(width 0.1)
				(type default)
			)
			(layer "F.Fab")
		)
		(fp_line
			(start -0.12065 -0.305054)
			(end -0.12065 -0.2794)
			(stroke
				(width 0.1)
				(type default)
			)
			(layer "F.Fab")
		)
		(pad "1" smd circle
			(at -0.40005 0 270)
			(size 0 0)
			(layers "F.Cu" "F.Mask" "F.Paste")
			(net "RST_PEX1_S0_PERST_N")
		)
		(pad "2" smd circle
			(at 0.40005 0 270)
			(size 0 0)
			(layers "F.Cu" "F.Mask" "F.Paste")
			(net "RST_PEX1_S0_PERST_R_N")
		)
	)
)
